# TIMECARD (Time Appliance Project (Time Card)) — schematic netlist excerpt (pin names and nets, part order shuffled) for the footprints in the layout excerpt that follows; sources: Cadence DE-HDL packaged netlist, KiCad conversion of R4006-B0001-02_R01.brd

SP37  SOLDER_PREFORM  pkg 0201_SOLDER_PREFORM_4MIL  page 34 : \1\ = NC ; \2\ = NC

DS15  LED_4P_V14  pkg SMC_DS4_098X039  page 26
  \1\  = UNNAMED_14_LED4PV14_I266_1
  \2\  = XP3R3V_FPGA
  \3\  = UNNAMED_14_LED4PV14_I266_3
  \4\  = UNNAMED_14_LED4PV14_I266_4

(kicad_pcb
	(version 20260206)
	(generator "pcbnew")
	(generator_version "10.0")
	(general
		(thickness 1.6)
		(legacy_teardrops no)
	)
	(paper "A4")
	(title_block
		(title "timecard-production-celestica-r4006 — R4006-B0001-02_R01.brd")
		(comment 1 "Time Appliance Project (Time Card) / footprints 116-117 of 1113")
	)
	(layers
		(0 "F.Cu" signal "TOP")
		(4 "In1.Cu" signal "L02_GND1")
		(6 "In2.Cu" signal "L03_SIG1")
		(8 "In3.Cu" signal "L04_GND2")
		(10 "In4.Cu" signal "L05_VCC1")
		(12 "In5.Cu" signal "L06_VCC2")
		(14 "In6.Cu" signal "L07_GND3")
		(16 "In7.Cu" signal "L08_SIG2")
		(18 "In8.Cu" signal "L09_GND4")
		(2 "B.Cu" signal "BOTTOM")
		(9 "F.Adhes" user "F.Adhesive")
		(11 "B.Adhes" user "B.Adhesive")
		(13 "F.Paste" user "Package Geometry/Pastemask Top")
		(15 "B.Paste" user "Package Geometry/Pastemask Bottom")
		(5 "F.SilkS" user "Ref Des/Silkscreen Top")
		(7 "B.SilkS" user "Ref Des/Silkscreen Bottom")
		(1 "F.Mask" user "Board Geometry/Soldermask Top")
		(3 "B.Mask" user "Board Geometry/Soldermask Bottom")
		(17 "Dwgs.User" user "User.Drawings")
		(19 "Cmts.User" user "User.Comments")
		(21 "Eco1.User" user "User.Eco1")
		(23 "Eco2.User" user "User.Eco2")
		(25 "Edge.Cuts" user "Board Geometry/Outline")
		(27 "Margin" user)
		(31 "F.CrtYd" user "Package Geometry/Place Bound Top")
		(29 "B.CrtYd" user "Package Geometry/Place Bound Bottom")
		(35 "F.Fab" user "Ref Des/Assembly Top")
		(33 "B.Fab" user "Ref Des/Assembly Bottom")
	)
	(footprint ""
		(layer "F.Cu")
		(at 1.500124 -24.5999 90)
		(property "Reference" "DS15"
			(at 2.66573 0.785876 0)
			(unlocked yes)
			(layer "F.SilkS")
			(effects
				(font
					(size 0.7874 0.5842)
					(thickness 0.1524)
				)
			)
		)
		(property "Value" ""
			(at 0 0 90)
			(layer "F.Fab")
			(effects
				(font
					(size 1.27 1.27)
				)
			)
		)
		(property "User Part Number" "PARTNUM*"
			(at 0.015494 4.486402 90)
			(unlocked yes)
			(layer "Cmts.User")
			(hide yes)
			(effects
				(font
					(size 0.7874 0.5842)
					(thickness 0.1524)
				)
			)
		)
		(property "Device Type" "LED_4P_V14-G170-10189-01"
			(at 0.015494 3.292602 90)
			(unlocked yes)
			(layer "F.Fab")
			(hide yes)
			(effects
				(font
					(size 0.7874 0.5842)
					(thickness 0.1524)
				)
			)
		)
		(duplicate_pad_numbers_are_jumpers no)
		(fp_line
			(start 1.378966 -0.829056)
			(end -1.378966 -0.829056)
			(stroke
				(width 0.1)
				(type default)
			)
			(layer "F.SilkS")
		)
		(fp_line
			(start -1.378966 -0.829056)
			(end -1.378966 -0.452628)
			(stroke
				(width 0.1)
				(type default)
			)
			(layer "F.SilkS")
		)
		(fp_line
			(start 1.998218 -0.452628)
			(end 1.378966 -0.452628)
			(stroke
				(width 0.1)
				(type default)
			)
			(layer "F.SilkS")
		)
		(fp_line
			(start 1.378966 -0.452628)
			(end 1.378966 -0.829056)
			(stroke
				(width 0.1)
				(type default)
			)
			(layer "F.SilkS")
		)
		(fp_line
			(start -1.378966 -0.452628)
			(end -1.998218 -0.452628)
			(stroke
				(width 0.1)
				(type default)
			)
			(layer "F.SilkS")
		)
		(fp_line
			(start -1.998218 -0.452628)
			(end -1.998218 1.103884)
			(stroke
				(width 0.1)
				(type default)
			)
			(layer "F.SilkS")
		)
		(fp_line
			(start 1.998218 1.103884)
			(end 1.998218 -0.452628)
			(stroke
				(width 0.1)
				(type default)
			)
			(layer "F.SilkS")
		)
		(fp_line
			(start -1.998218 1.103884)
			(end 1.998218 1.103884)
			(stroke
				(width 0.1)
				(type default)
			)
			(layer "F.SilkS")
		)
		(fp_poly
			(pts
				(xy 0.918464 -1.698498) (xy 1.223264 -1.46939) (xy 0.994664 -1.46939) (xy 0.994664 -1.24079) (xy 0.842264 -1.24079)
				(xy 0.842264 -1.46939) (xy 0.613664 -1.46939)
			)
			(stroke
				(width 0)
				(type default)
			)
			(fill yes)
			(layer "F.SilkS")
		)
		(fp_poly
			(pts
				(xy -0.73406 -1.677416) (xy -0.42926 -1.448308) (xy -0.65786 -1.448308) (xy -0.65786 -1.219708)
				(xy -0.81026 -1.219708) (xy -0.81026 -1.448308) (xy -1.03886 -1.448308)
			)
			(stroke
				(width 0)
				(type default)
			)
			(fill yes)
			(layer "F.SilkS")
		)
		(fp_poly
			(pts
				(xy -2.252218 1.357884) (xy -2.252218 -0.706628) (xy -1.632966 -0.706628) (xy -1.632966 -1.083056)
				(xy 1.632966 -1.083056) (xy 1.632966 -0.706628) (xy 2.252218 -0.706628) (xy 2.252218 1.357884)
			)
			(stroke
				(width 0)
				(type default)
			)
			(fill no)
			(layer "F.CrtYd")
		)
		(fp_line
			(start 1.124966 -0.575056)
			(end -1.124966 -0.575056)
			(stroke
				(width 0.1)
				(type default)
			)
			(layer "F.Fab")
		)
		(fp_line
			(start -1.124966 -0.575056)
			(end -1.124966 -0.075184)
			(stroke
				(width 0.1)
				(type default)
			)
			(layer "F.Fab")
		)
		(fp_line
			(start 1.325118 -0.075184)
			(end 1.124966 -0.075184)
			(stroke
				(width 0.1)
				(type default)
			)
			(layer "F.Fab")
		)
		(fp_line
			(start 1.124966 -0.075184)
			(end 1.124966 -0.575056)
			(stroke
				(width 0.1)
				(type default)
			)
			(layer "F.Fab")
		)
		(fp_line
			(start -1.124966 -0.075184)
			(end -1.325118 -0.075184)
			(stroke
				(width 0.1)
				(type default)
			)
			(layer "F.Fab")
		)
		(fp_line
			(start -1.325118 -0.075184)
			(end -1.325118 0.574802)
			(stroke
				(width 0.1)
				(type default)
			)
			(layer "F.Fab")
		)
		(fp_line
			(start 1.325118 0.574802)
			(end 1.325118 -0.075184)
			(stroke
				(width 0.1)
				(type default)
			)
			(layer "F.Fab")
		)
		(fp_line
			(start -1.325118 0.574802)
			(end 1.325118 0.574802)
			(stroke
				(width 0.1)
				(type default)
			)
			(layer "F.Fab")
		)
		(fp_poly
			(pts
				(xy 0.918464 -1.698498) (xy 1.223264 -1.46939) (xy 0.994664 -1.46939) (xy 0.994664 -1.24079) (xy 0.842264 -1.24079)
				(xy 0.842264 -1.46939) (xy 0.613664 -1.46939)
			)
			(stroke
				(width 0)
				(type default)
			)
			(fill yes)
			(layer "F.Fab")
		)
		(fp_poly
			(pts
				(xy -0.73406 -1.677416) (xy -0.42926 -1.448308) (xy -0.65786 -1.448308) (xy -0.65786 -1.219708)
				(xy -0.81026 -1.219708) (xy -0.81026 -1.448308) (xy -1.03886 -1.448308)
			)
			(stroke
				(width 0)
				(type default)
			)
			(fill yes)
			(layer "F.Fab")
		)
		(fp_text user "1"
			(at -2.2479 0.182626 90)
			(unlocked yes)
			(layer "F.SilkS")
			(effects
				(font
					(size 0.635 0.4064)
					(thickness 0.1524)
				)
			)
		)
		(fp_text user "3"
			(at 0.44196 1.833626 90)
			(unlocked yes)
			(layer "F.SilkS")
			(effects
				(font
					(size 0.635 0.4064)
					(thickness 0.1524)
				)
			)
		)
		(fp_text user "2"
			(at -0.8509 1.833626 90)
			(unlocked yes)
			(layer "F.SilkS")
			(effects
				(font
					(size 0.635 0.4064)
					(thickness 0.1524)
				)
			)
		)
		(fp_text user "4"
			(at 1.93929 1.420876 0)
			(unlocked yes)
			(layer "F.Fab")
			(effects
				(font
					(size 0.7874 0.5842)
					(thickness 0.1524)
				)
			)
		)
		(fp_text user "3"
			(at 0.79629 1.420876 0)
			(unlocked yes)
			(layer "F.Fab")
			(effects
				(font
					(size 0.7874 0.5842)
					(thickness 0.1524)
				)
			)
		)
		(fp_text user "2"
			(at -0.34671 1.420876 0)
			(unlocked yes)
			(layer "F.Fab")
			(effects
				(font
					(size 0.7874 0.5842)
					(thickness 0.1524)
				)
			)
		)
		(fp_text user "1"
			(at -1.39827 1.547876 0)
			(unlocked yes)
			(layer "F.Fab")
			(effects
				(font
					(size 0.7874 0.5842)
					(thickness 0.1524)
				)
			)
		)
		(pad "1" smd rect
			(at -1.325118 0.245872 90)
			(size 0.8382 0.889)
			(layers "F.Cu" "F.Mask" "F.Paste")
			(net "UNNAMED_14_LED4PV14_I266_1")
		)
		(pad "2" smd rect
			(at -0.424942 0.595884 90)
			(size 0.4572 0.508)
			(layers "F.Cu" "F.Mask" "F.Paste")
			(net "XP3R3V_FPGA")
		)
		(pad "3" smd rect
			(at 0.424942 0.595884 90)
			(size 0.4572 0.508)
			(layers "F.Cu" "F.Mask" "F.Paste")
			(net "UNNAMED_14_LED4PV14_I266_3")
		)
		(pad "4" smd rect
			(at 1.325118 0.245872 90)
			(size 0.8382 0.889)
			(layers "F.Cu" "F.Mask" "F.Paste")
			(net "UNNAMED_14_LED4PV14_I266_4")
		)
	)
	(footprint ""
		(layer "F.Cu")
		(at 60.325 -133.477)
		(property "Reference" "SP37"
			(at 0 0 0)
			(layer "F.SilkS")
			(hide yes)
			(effects
				(font
					(size 1.27 1.27)
				)
			)
		)
		(property "Value" ""
			(at 0 0 0)
			(layer "F.Fab")
			(effects
				(font
					(size 1.27 1.27)
				)
			)
		)
		(duplicate_pad_numbers_are_jumpers no)
	)
)
